#ISCELL
  pure_quanta quanta_title_block_c *
  *
#CELL
  pure_quanta lcmxo3lf2100c5bg256c *
  page38_i1
#ISCELL
  logical_power universal_power *
  page38_i3
